# T6G (Grand Teton) — schematic netlist excerpt (pin names and nets, part order shuffled) for the footprints in the layout excerpt that follows; sources: Cadence DE-HDL packaged netlist, KiCad conversion of 04192023_DAF0TMB3IC0_F0TG_MB_C_brd_V02_OCP.brd

C2121  Q_CAP  22UF 4V 20% X6S  pkg C0402  page 74 : A = PVDD11_S3_P1 ; B = GND
R968  Q_RES  1K 1% EMPTY  pkg 0201LF  page 276 : A = P1V8_CPU0_RT_1D ; B = RT_CPU0_P0_ADDR1
C1516  Q_CAP  0.1UF 16V 10% X7R  pkg C0402  page 173 : A = PVDD18_S5_P0 ; B = GND

(kicad_pcb
	(version 20260206)
	(generator "pcbnew")
	(generator_version "10.0")
	(general
		(thickness 1.6)
		(legacy_teardrops no)
	)
	(paper "A4")
	(title_block
		(title "04192023_DAF0TMB3IC0_F0TG_MB_C_brd_V02_OCP.brd")
		(comment 1 "Grand Teton / footprints 4237-4239 of 8354")
	)
	(layers
		(0 "F.Cu" signal "TOP")
		(4 "In1.Cu" signal "GND")
		(6 "In2.Cu" signal "IN1")
		(8 "In3.Cu" signal "GND1")
		(10 "In4.Cu" signal "IN2")
		(12 "In5.Cu" signal "GND2")
		(14 "In6.Cu" signal "IN3")
		(16 "In7.Cu" signal "GND3")
		(18 "In8.Cu" signal "VCC")
		(20 "In9.Cu" signal "VCC1")
		(22 "In10.Cu" signal "GND4")
		(24 "In11.Cu" signal "IN4")
		(26 "In12.Cu" signal "GND5")
		(28 "In13.Cu" signal "IN5")
		(30 "In14.Cu" signal "GND6")
		(32 "In15.Cu" signal "IN6")
		(34 "In16.Cu" signal "GND7")
		(2 "B.Cu" signal "BOTTOM")
		(9 "F.Adhes" user "F.Adhesive")
		(11 "B.Adhes" user "B.Adhesive")
		(13 "F.Paste" user "Package Geometry/Pastemask Top")
		(15 "B.Paste" user "Package Geometry/Pastemask Bottom")
		(5 "F.SilkS" user "Ref Des/Silkscreen Top")
		(7 "B.SilkS" user "Ref Des/Silkscreen Bottom")
		(1 "F.Mask" user "Board Geometry/Soldermask Top")
		(3 "B.Mask" user "Board Geometry/Soldermask Bottom")
		(17 "Dwgs.User" user "User.Drawings")
		(19 "Cmts.User" user "User.Comments")
		(21 "Eco1.User" user "User.Eco1")
		(23 "Eco2.User" user "User.Eco2")
		(25 "Edge.Cuts" user "Board Geometry/Outline")
		(27 "Margin" user)
		(31 "F.CrtYd" user "Package Geometry/Place Bound Top")
		(29 "B.CrtYd" user "Package Geometry/Place Bound Bottom")
		(35 "F.Fab" user "Ref Des/Assembly Top")
		(33 "B.Fab" user "Ref Des/Assembly Bottom")
	)
	(footprint ""
		(layer "F.Cu")
		(at 109.577124 -261.748016 -90)
		(property "Reference" "C2121"
			(at 0 0 270)
			(layer "F.SilkS")
			(hide yes)
			(effects
				(font
					(size 1.27 1.27)
				)
			)
		)
		(property "Value" ""
			(at 0 0 270)
			(layer "F.Fab")
			(effects
				(font
					(size 1.27 1.27)
				)
			)
		)
		(duplicate_pad_numbers_are_jumpers no)
		(fp_line
			(start -0.7874 0.4064)
			(end -0.7874 -0.4064)
			(stroke
				(width 0.1524)
				(type default)
			)
			(layer "F.SilkS")
		)
		(fp_line
			(start 0.7874 0.4064)
			(end -0.7874 0.4064)
			(stroke
				(width 0.1524)
				(type default)
			)
			(layer "F.SilkS")
		)
		(fp_line
			(start -0.7874 -0.4064)
			(end 0.7874 -0.4064)
			(stroke
				(width 0.1524)
				(type default)
			)
			(layer "F.SilkS")
		)
		(fp_line
			(start 0.7874 -0.4064)
			(end 0.7874 0.4064)
			(stroke
				(width 0.1524)
				(type default)
			)
			(layer "F.SilkS")
		)
		(fp_line
			(start -0.67945 0.3048)
			(end -0.67945 -0.305054)
			(stroke
				(width 0.1)
				(type default)
			)
			(layer "F.Fab")
		)
		(fp_line
			(start -0.12065 0.3048)
			(end -0.67945 0.3048)
			(stroke
				(width 0.1)
				(type default)
			)
			(layer "F.Fab")
		)
		(fp_line
			(start 0.120396 0.3048)
			(end 0.120396 0.2794)
			(stroke
				(width 0.1)
				(type default)
			)
			(layer "F.Fab")
		)
		(fp_line
			(start 0.67945 0.3048)
			(end 0.120396 0.3048)
			(stroke
				(width 0.1)
				(type default)
			)
			(layer "F.Fab")
		)
		(fp_line
			(start -0.12065 0.2794)
			(end -0.12065 0.3048)
			(stroke
				(width 0.1)
				(type default)
			)
			(layer "F.Fab")
		)
		(fp_line
			(start 0.120396 0.2794)
			(end -0.12065 0.2794)
			(stroke
				(width 0.1)
				(type default)
			)
			(layer "F.Fab")
		)
		(fp_line
			(start -0.12065 -0.2794)
			(end 0.12065 -0.2794)
			(stroke
				(width 0.1)
				(type default)
			)
			(layer "F.Fab")
		)
		(fp_line
			(start 0.12065 -0.2794)
			(end 0.12065 -0.3048)
			(stroke
				(width 0.1)
				(type default)
			)
			(layer "F.Fab")
		)
		(fp_line
			(start 0.12065 -0.3048)
			(end 0.67945 -0.3048)
			(stroke
				(width 0.1)
				(type default)
			)
			(layer "F.Fab")
		)
		(fp_line
			(start 0.67945 -0.3048)
			(end 0.67945 0.3048)
			(stroke
				(width 0.1)
				(type default)
			)
			(layer "F.Fab")
		)
		(fp_line
			(start -0.67945 -0.305054)
			(end -0.12065 -0.305054)
			(stroke
				(width 0.1)
				(type default)
			)
			(layer "F.Fab")
		)
		(fp_line
			(start -0.12065 -0.305054)
			(end -0.12065 -0.2794)
			(stroke
				(width 0.1)
				(type default)
			)
			(layer "F.Fab")
		)
		(pad "1" smd circle
			(at -0.40005 0 270)
			(size 0 0)
			(layers "F.Cu" "F.Mask" "F.Paste")
			(net "PVDD11_S3_P1")
		)
		(pad "2" smd circle
			(at 0.40005 0 270)
			(size 0 0)
			(layers "F.Cu" "F.Mask" "F.Paste")
			(net "GND")
		)
	)
	(footprint ""
		(layer "F.Cu")
		(at 255.13284 -92.719144 -90)
		(property "Reference" "C1516"
			(at 0 0 270)
			(layer "F.SilkS")
			(hide yes)
			(effects
				(font
					(size 1.27 1.27)
				)
			)
		)
		(property "Value" ""
			(at 0 0 270)
			(layer "F.Fab")
			(effects
				(font
					(size 1.27 1.27)
				)
			)
		)
		(duplicate_pad_numbers_are_jumpers no)
		(fp_line
			(start -0.7874 0.4064)
			(end -0.7874 -0.4064)
			(stroke
				(width 0.1524)
				(type default)
			)
			(layer "F.SilkS")
		)
		(fp_line
			(start 0.7874 0.4064)
			(end -0.7874 0.4064)
			(stroke
				(width 0.1524)
				(type default)
			)
			(layer "F.SilkS")
		)
		(fp_line
			(start -0.7874 -0.4064)
			(end 0.7874 -0.4064)
			(stroke
				(width 0.1524)
				(type default)
			)
			(layer "F.SilkS")
		)
		(fp_line
			(start 0.7874 -0.4064)
			(end 0.7874 0.4064)
			(stroke
				(width 0.1524)
				(type default)
			)
			(layer "F.SilkS")
		)
		(fp_line
			(start -0.67945 0.3048)
			(end -0.67945 -0.305054)
			(stroke
				(width 0.1)
				(type default)
			)
			(layer "F.Fab")
		)
		(fp_line
			(start -0.12065 0.3048)
			(end -0.67945 0.3048)
			(stroke
				(width 0.1)
				(type default)
			)
			(layer "F.Fab")
		)
		(fp_line
			(start 0.120396 0.3048)
			(end 0.120396 0.2794)
			(stroke
				(width 0.1)
				(type default)
			)
			(layer "F.Fab")
		)
		(fp_line
			(start 0.67945 0.3048)
			(end 0.120396 0.3048)
			(stroke
				(width 0.1)
				(type default)
			)
			(layer "F.Fab")
		)
		(fp_line
			(start -0.12065 0.2794)
			(end -0.12065 0.3048)
			(stroke
				(width 0.1)
				(type default)
			)
			(layer "F.Fab")
		)
		(fp_line
			(start 0.120396 0.2794)
			(end -0.12065 0.2794)
			(stroke
				(width 0.1)
				(type default)
			)
			(layer "F.Fab")
		)
		(fp_line
			(start -0.12065 -0.2794)
			(end 0.12065 -0.2794)
			(stroke
				(width 0.1)
				(type default)
			)
			(layer "F.Fab")
		)
		(fp_line
			(start 0.12065 -0.2794)
			(end 0.12065 -0.3048)
			(stroke
				(width 0.1)
				(type default)
			)
			(layer "F.Fab")
		)
		(fp_line
			(start 0.12065 -0.3048)
			(end 0.67945 -0.3048)
			(stroke
				(width 0.1)
				(type default)
			)
			(layer "F.Fab")
		)
		(fp_line
			(start 0.67945 -0.3048)
			(end 0.67945 0.3048)
			(stroke
				(width 0.1)
				(type default)
			)
			(layer "F.Fab")
		)
		(fp_line
			(start -0.67945 -0.305054)
			(end -0.12065 -0.305054)
			(stroke
				(width 0.1)
				(type default)
			)
			(layer "F.Fab")
		)
		(fp_line
			(start -0.12065 -0.305054)
			(end -0.12065 -0.2794)
			(stroke
				(width 0.1)
				(type default)
			)
			(layer "F.Fab")
		)
		(pad "1" smd circle
			(at -0.40005 0 270)
			(size 0 0)
			(layers "F.Cu" "F.Mask" "F.Paste")
			(net "PVDD18_S5_P0")
		)
		(pad "2" smd circle
			(at 0.40005 0 270)
			(size 0 0)
			(layers "F.Cu" "F.Mask" "F.Paste")
			(net "GND")
		)
	)
	(footprint ""
		(layer "F.Cu")
		(at 326.967342 -391.0584 180)
		(property "Reference" "R968"
			(at 0 0 180)
			(layer "F.SilkS")
			(hide yes)
			(effects
				(font
					(size 1.27 1.27)
				)
			)
		)
		(property "Value" ""
			(at 0 0 180)
			(layer "F.Fab")
			(effects
				(font
					(size 1.27 1.27)
				)
			)
		)
		(duplicate_pad_numbers_are_jumpers no)
		(fp_line
			(start 0.32512 0.175006)
			(end -0.32512 0.175006)
			(stroke
				(width 0.1)
				(type default)
			)
			(layer "F.Fab")
		)
		(fp_line
			(start 0.32512 -0.175006)
			(end 0.32512 0.175006)
			(stroke
				(width 0.1)
				(type default)
			)
			(layer "F.Fab")
		)
		(fp_line
			(start -0.32512 0.175006)
			(end -0.32512 -0.175006)
			(stroke
				(width 0.1)
				(type default)
			)
			(layer "F.Fab")
		)
		(fp_line
			(start -0.32512 -0.175006)
			(end 0.32512 -0.175006)
			(stroke
				(width 0.1)
				(type default)
			)
			(layer "F.Fab")
		)
		(pad "1" smd rect
			(at -0.2667 0 180)
			(size 0.3048 0.381)
			(layers "F.Cu" "F.Mask" "F.Paste")
			(net "P1V8_CPU0_RT_1D")
		)
		(pad "2" smd rect
			(at 0.2667 0)
			(size 0.3048 0.381)
			(layers "F.Cu" "F.Mask" "F.Paste")
			(net "RT_CPU0_P0_ADDR1")
		)
	)
)
